# BASEBOARD_FAB2 (Tioga Pass) — schematic netlist excerpt (pin names and nets, part order shuffled) for the footprints in the layout excerpt that follows; sources: Cadence DE-HDL packaged netlist, KiCad conversion of Wiwynn_Tioga_Pass_MB.brd

C7G20  CAP  0.22UF 16V 10% X7R  pkg 0402  page 105 : A = P3E_CPU0_PE2_SS_TXP<8> ; B = P3E_CPU0_PE2_SS_C_TXP<8>
C25W3  CAP  1.0UF 16V 10% X6S  pkg 0402  page 151 : A = P1V2_AUX_BMC ; B = GND

(kicad_pcb
	(version 20260206)
	(generator "pcbnew")
	(generator_version "10.0")
	(general
		(thickness 1.6)
		(legacy_teardrops no)
	)
	(paper "A4")
	(title_block
		(title "Wiwynn_Tioga_Pass_MB.brd")
		(comment 1 "Tioga Pass / footprints 2176-2177 of 4770")
	)
	(layers
		(0 "F.Cu" signal "TOP")
		(4 "In1.Cu" signal "L2GND")
		(6 "In2.Cu" signal "L3")
		(8 "In3.Cu" signal "L4GND")
		(10 "In4.Cu" signal "L5")
		(12 "In5.Cu" signal "L6GND")
		(14 "In6.Cu" signal "L7VCC")
		(16 "In7.Cu" signal "L8VCC")
		(18 "In8.Cu" signal "L9GND")
		(20 "In9.Cu" signal "L10")
		(22 "In10.Cu" signal "L11GND")
		(24 "In11.Cu" signal "L12")
		(26 "In12.Cu" signal "L13GND")
		(2 "B.Cu" signal "BOTTOM")
		(9 "F.Adhes" user "F.Adhesive")
		(11 "B.Adhes" user "B.Adhesive")
		(13 "F.Paste" user "Package Geometry/Pastemask Top")
		(15 "B.Paste" user "Package Geometry/Pastemask Bottom")
		(5 "F.SilkS" user "Ref Des/Silkscreen Top")
		(7 "B.SilkS" user "Ref Des/Silkscreen Bottom")
		(1 "F.Mask" user "Board Geometry/Soldermask Top")
		(3 "B.Mask" user "Board Geometry/Soldermask Bottom")
		(17 "Dwgs.User" user "User.Drawings")
		(19 "Cmts.User" user "User.Comments")
		(21 "Eco1.User" user "User.Eco1")
		(23 "Eco2.User" user "User.Eco2")
		(25 "Edge.Cuts" user "Board Geometry/Outline")
		(27 "Margin" user)
		(31 "F.CrtYd" user "Package Geometry/Place Bound Top")
		(29 "B.CrtYd" user "Package Geometry/Place Bound Bottom")
		(35 "F.Fab" user "Ref Des/Assembly Top")
		(33 "B.Fab" user "Ref Des/Assembly Bottom")
	)
	(footprint ""
		(layer "F.Cu")
		(at 378.926344 -10.941558)
		(property "Reference" "C7G20"
			(at 0 0 0)
			(layer "F.SilkS")
			(hide yes)
			(effects
				(font
					(size 1.27 1.27)
				)
			)
		)
		(property "Value" ""
			(at 0 0 0)
			(layer "F.Fab")
			(effects
				(font
					(size 1.27 1.27)
				)
			)
		)
		(duplicate_pad_numbers_are_jumpers no)
		(fp_rect
			(start -0.3048 0.9906)
			(end 0.3048 -0.1016)
			(stroke
				(width 0)
				(type default)
			)
			(fill no)
			(layer "F.CrtYd")
		)
		(fp_line
			(start -0.3048 -0.1016)
			(end -0.3048 0.9906)
			(stroke
				(width 0.1)
				(type default)
			)
			(layer "F.Fab")
		)
		(fp_line
			(start -0.3048 0.9906)
			(end 0.3048 0.9906)
			(stroke
				(width 0.1)
				(type default)
			)
			(layer "F.Fab")
		)
		(fp_line
			(start 0.3048 -0.1016)
			(end -0.3048 -0.1016)
			(stroke
				(width 0.1)
				(type default)
			)
			(layer "F.Fab")
		)
		(fp_line
			(start 0.3048 0.9906)
			(end 0.3048 -0.1016)
			(stroke
				(width 0.1)
				(type default)
			)
			(layer "F.Fab")
		)
		(pad "1" smd rect
			(at 0 0)
			(size 0.508 0.508)
			(layers "F.Cu" "F.Mask" "F.Paste")
			(net "P3E_CPU0_PE2_SS_TXP<8>")
		)
		(pad "2" smd rect
			(at 0 0.889)
			(size 0.508 0.508)
			(layers "F.Cu" "F.Mask" "F.Paste")
			(net "P3E_CPU0_PE2_SS_C_TXP<8>")
		)
		(zone
			(layer "F.Cu")
			(hatch none 0.5)
			(connect_pads
				(clearance 0)
			)
			(min_thickness 0.25)
			(keepout
				(tracks allowed)
				(vias not_allowed)
				(pads allowed)
				(copperpour not_allowed)
				(footprints allowed)
			)
			(placement
				(enabled no)
				(sheetname "")
			)
			(fill
				(thermal_gap 0.5)
				(thermal_bridge_width 0.5)
				(island_removal_mode 0)
			)
			(polygon
				(pts
					(xy 378.672344 -10.306558) (xy 379.180344 -10.306558) (xy 379.180344 -10.687558) (xy 378.672344 -10.687558)
				)
			)
		)
	)
	(footprint ""
		(layer "F.Cu")
		(at 452.247 -28.7655)
		(property "Reference" "C25W3"
			(at -0.8382 -0.67818 0)
			(unlocked yes)
			(layer "F.SilkS")
			(effects
				(font
					(size 0.4064 0.254)
					(thickness 0.1524)
				)
				(justify left)
			)
		)
		(property "Value" ""
			(at 0 0 0)
			(layer "F.Fab")
			(effects
				(font
					(size 1.27 1.27)
				)
			)
		)
		(duplicate_pad_numbers_are_jumpers no)
		(fp_poly
			(pts
				(xy 0.3048 -0.1016) (xy 0.3048 0.9906) (xy -0.3048 0.9906) (xy -0.3048 -0.1016)
			)
			(stroke
				(width 0)
				(type default)
			)
			(fill no)
			(layer "F.CrtYd")
		)
		(fp_line
			(start -0.3048 -0.1016)
			(end -0.3048 0.9906)
			(stroke
				(width 0.1)
				(type default)
			)
			(layer "F.Fab")
		)
		(fp_line
			(start -0.3048 0.9906)
			(end 0.3048 0.9906)
			(stroke
				(width 0.1)
				(type default)
			)
			(layer "F.Fab")
		)
		(fp_line
			(start 0.3048 -0.1016)
			(end -0.3048 -0.1016)
			(stroke
				(width 0.1)
				(type default)
			)
			(layer "F.Fab")
		)
		(fp_line
			(start 0.3048 0.9906)
			(end 0.3048 -0.1016)
			(stroke
				(width 0.1)
				(type default)
			)
			(layer "F.Fab")
		)
		(pad "1" smd rect
			(at 0 0)
			(size 0.508 0.508)
			(layers "F.Cu" "F.Mask" "F.Paste")
			(net "P1V2_AUX_BMC")
		)
		(pad "2" smd rect
			(at 0 0.889)
			(size 0.508 0.508)
			(layers "F.Cu" "F.Mask" "F.Paste")
			(net "GND")
		)
		(zone
			(layer "F.Cu")
			(hatch none 0.5)
			(connect_pads
				(clearance 0)
			)
			(min_thickness 0.25)
			(keepout
				(tracks allowed)
				(vias not_allowed)
				(pads allowed)
				(copperpour not_allowed)
				(footprints allowed)
			)
			(placement
				(enabled no)
				(sheetname "")
			)
			(fill
				(thermal_gap 0.5)
				(thermal_bridge_width 0.5)
				(island_removal_mode 0)
			)
			(polygon
				(pts
					(xy 451.993 -28.5115) (xy 452.501 -28.5115) (xy 452.501 -28.1305) (xy 451.993 -28.1305)
				)
			)
		)
		(zone
			(layer "F.Cu")
			(hatch none 0.5)
			(connect_pads
				(clearance 0)
			)
			(min_thickness 0.25)
			(keepout
				(tracks not_allowed)
				(vias allowed)
				(pads allowed)
				(copperpour not_allowed)
				(footprints allowed)
			)
			(placement
				(enabled no)
				(sheetname "")
			)
			(fill
				(thermal_gap 0.5)
				(thermal_bridge_width 0.5)
				(island_removal_mode 0)
			)
			(polygon
				(pts
					(xy 451.993 -28.1305) (xy 452.501 -28.1305) (xy 452.501 -28.5115) (xy 451.993 -28.5115)
				)
			)
		)
	)
)
